(kicad_pcb
	(version 20260206)
	(generator "pcbnew")
	(generator_version "10.0")
	(general
		(thickness 1.6)
		(legacy_teardrops no)
	)
	(paper "A4")
	(title_block
		(title "pdpb — Lightning_PDPB_BRD.brd")
		(comment 1 "Lightning (Wiwynn / Facebook NVMe JBOF) / footprints 158-164 of 1140")
	)
	(layers
		(0 "F.Cu" signal "TOP")
		(4 "In1.Cu" signal "L2GND")
		(6 "In2.Cu" signal "L3")
		(8 "In3.Cu" signal "L4VCC")
		(10 "In4.Cu" signal "L5VCC")
		(12 "In5.Cu" signal "L6")
		(14 "In6.Cu" signal "L7GND")
		(2 "B.Cu" signal "BOTTOM")
		(9 "F.Adhes" user "F.Adhesive")
		(11 "B.Adhes" user "B.Adhesive")
		(13 "F.Paste" user "Package Geometry/Pastemask Top")
		(15 "B.Paste" user "Package Geometry/Pastemask Bottom")
		(5 "F.SilkS" user "Ref Des/Silkscreen Top")
		(7 "B.SilkS" user "Ref Des/Silkscreen Bottom")
		(1 "F.Mask" user "Board Geometry/Soldermask Top")
		(3 "B.Mask" user "Board Geometry/Soldermask Bottom")
		(17 "Dwgs.User" user "User.Drawings")
		(19 "Cmts.User" user "User.Comments")
		(21 "Eco1.User" user "User.Eco1")
		(23 "Eco2.User" user "User.Eco2")
		(25 "Edge.Cuts" user "Board Geometry/Outline")
		(27 "Margin" user)
		(31 "F.CrtYd" user "Package Geometry/Place Bound Top")
		(29 "B.CrtYd" user "Package Geometry/Place Bound Bottom")
		(35 "F.Fab" user "Ref Des/Assembly Top")
		(33 "B.Fab" user "Ref Des/Assembly Bottom")
	)
	(footprint ""
		(layer "F.Cu")
		(at 87.503 -110.236 180)
		(property "Reference" "R9059"
			(at 0 0 180)
			(layer "F.SilkS")
			(hide yes)
			(effects
				(font
					(size 1.27 1.27)
				)
			)
		)
		(property "Value" "27R2F-GP"
			(at 0.064008 -3.993896 180)
			(unlocked yes)
			(layer "F.Fab")
			(hide yes)
			(effects
				(font
					(size 1.016 1.016)
					(thickness 0.1524)
				)
			)
		)
		(property "Device Type" "R402H16"
			(at 0.064008 -5.517896 180)
			(unlocked yes)
			(layer "F.Fab")
			(hide yes)
			(effects
				(font
					(size 1.016 1.016)
					(thickness 0.1524)
				)
			)
		)
		(duplicate_pad_numbers_are_jumpers no)
		(fp_line
			(start 0.508 -0.9398)
			(end -0.508 -0.9398)
			(stroke
				(width 0.1524)
				(type default)
			)
			(layer "F.SilkS")
		)
		(fp_line
			(start -0.508 -0.9398)
			(end -0.508 0.9398)
			(stroke
				(width 0.1524)
				(type default)
			)
			(layer "F.SilkS")
		)
		(fp_rect
			(start -0.508 0.9398)
			(end 0.508 -0.9398)
			(stroke
				(width 0)
				(type default)
			)
			(fill no)
			(layer "F.CrtYd")
		)
		(fp_rect
			(start -0.508 0.9398)
			(end 0.508 -0.9398)
			(stroke
				(width 0)
				(type default)
			)
			(fill no)
			(layer "F.Fab")
		)
		(pad "1" smd custom
			(at 0 -0.4445 180)
			(size 0.1397 0.1397)
			(layers "F.Cu" "F.Mask" "F.Paste")
			(net "PE_CLK_100M_DR13_1_R_P")
			(options
				(clearance outline)
				(anchor circle)
			)
			(primitives
				(gr_poly
					(pts
						(arc
							(start -0.1778 -0.2794)
							(mid -0.249642 -0.249642)
							(end -0.2794 -0.1778)
						)
						(arc
							(start -0.2794 0.1778)
							(mid -0.249642 0.249642)
							(end -0.1778 0.2794)
						)
						(arc
							(start 0.1778 0.2794)
							(mid 0.249642 0.249642)
							(end 0.2794 0.1778)
						)
						(arc
							(start 0.2794 -0.1778)
							(mid 0.249642 -0.249642)
							(end 0.1778 -0.2794)
						)
					)
					(width 0)
					(fill yes)
				)
			)
		)
		(pad "2" smd custom
			(at 0 0.4445 180)
			(size 0.1397 0.1397)
			(layers "F.Cu" "F.Mask" "F.Paste")
			(net "PE_CLK100M_DR13_1_P")
			(options
				(clearance outline)
				(anchor circle)
			)
			(primitives
				(gr_poly
					(pts
						(arc
							(start -0.1778 -0.2794)
							(mid -0.249642 -0.249642)
							(end -0.2794 -0.1778)
						)
						(arc
							(start -0.2794 0.1778)
							(mid -0.249642 0.249642)
							(end -0.1778 0.2794)
						)
						(arc
							(start 0.1778 0.2794)
							(mid 0.249642 0.249642)
							(end 0.2794 0.1778)
						)
						(arc
							(start 0.2794 -0.1778)
							(mid 0.249642 -0.249642)
							(end 0.1778 -0.2794)
						)
					)
					(width 0)
					(fill yes)
				)
			)
		)
	)
	(footprint ""
		(layer "F.Cu")
		(at 87.503 -440.436 180)
		(property "Reference" "R9063"
			(at 0 0 180)
			(layer "F.SilkS")
			(hide yes)
			(effects
				(font
					(size 1.27 1.27)
				)
			)
		)
		(property "Value" "27R2F-GP"
			(at 0.064008 -3.993896 180)
			(unlocked yes)
			(layer "F.Fab")
			(hide yes)
			(effects
				(font
					(size 1.016 1.016)
					(thickness 0.1524)
				)
			)
		)
		(property "Device Type" "R402H16"
			(at 0.064008 -5.517896 180)
			(unlocked yes)
			(layer "F.Fab")
			(hide yes)
			(effects
				(font
					(size 1.016 1.016)
					(thickness 0.1524)
				)
			)
		)
		(duplicate_pad_numbers_are_jumpers no)
		(fp_line
			(start 0.508 -0.9398)
			(end -0.508 -0.9398)
			(stroke
				(width 0.1524)
				(type default)
			)
			(layer "F.SilkS")
		)
		(fp_line
			(start -0.508 -0.9398)
			(end -0.508 0.9398)
			(stroke
				(width 0.1524)
				(type default)
			)
			(layer "F.SilkS")
		)
		(fp_rect
			(start -0.508 0.9398)
			(end 0.508 -0.9398)
			(stroke
				(width 0)
				(type default)
			)
			(fill no)
			(layer "F.CrtYd")
		)
		(fp_rect
			(start -0.508 0.9398)
			(end 0.508 -0.9398)
			(stroke
				(width 0)
				(type default)
			)
			(fill no)
			(layer "F.Fab")
		)
		(pad "1" smd custom
			(at 0 -0.4445 180)
			(size 0.1397 0.1397)
			(layers "F.Cu" "F.Mask" "F.Paste")
			(net "PE_CLK_100M_DR5_1_R_P")
			(options
				(clearance outline)
				(anchor circle)
			)
			(primitives
				(gr_poly
					(pts
						(arc
							(start -0.1778 -0.2794)
							(mid -0.249642 -0.249642)
							(end -0.2794 -0.1778)
						)
						(arc
							(start -0.2794 0.1778)
							(mid -0.249642 0.249642)
							(end -0.1778 0.2794)
						)
						(arc
							(start 0.1778 0.2794)
							(mid 0.249642 0.249642)
							(end 0.2794 0.1778)
						)
						(arc
							(start 0.2794 -0.1778)
							(mid 0.249642 -0.249642)
							(end 0.1778 -0.2794)
						)
					)
					(width 0)
					(fill yes)
				)
			)
		)
		(pad "2" smd custom
			(at 0 0.4445 180)
			(size 0.1397 0.1397)
			(layers "F.Cu" "F.Mask" "F.Paste")
			(net "PE_CLK100M_DR5_1_P")
			(options
				(clearance outline)
				(anchor circle)
			)
			(primitives
				(gr_poly
					(pts
						(arc
							(start -0.1778 -0.2794)
							(mid -0.249642 -0.249642)
							(end -0.2794 -0.1778)
						)
						(arc
							(start -0.2794 0.1778)
							(mid -0.249642 0.249642)
							(end -0.1778 0.2794)
						)
						(arc
							(start 0.1778 0.2794)
							(mid 0.249642 0.249642)
							(end 0.2794 0.1778)
						)
						(arc
							(start 0.2794 -0.1778)
							(mid 0.249642 -0.249642)
							(end 0.1778 -0.2794)
						)
					)
					(width 0)
					(fill yes)
				)
			)
		)
	)
	(footprint ""
		(layer "F.Cu")
		(at 222.123 -297.688 180)
		(property "Reference" "PC1192"
			(at 0 0 180)
			(layer "F.SilkS")
			(hide yes)
			(effects
				(font
					(size 1.27 1.27)
				)
			)
		)
		(property "Value" "SCD1U50V3KX-GP"
			(at 0 -2.8194 180)
			(unlocked yes)
			(layer "F.Fab")
			(hide yes)
			(effects
				(font
					(size 1.016 1.016)
					(thickness 0.1524)
				)
			)
		)
		(property "Device Type" "C603H36"
			(at 0 -4.3434 180)
			(unlocked yes)
			(layer "F.Fab")
			(hide yes)
			(effects
				(font
					(size 1.016 1.016)
					(thickness 0.1524)
				)
			)
		)
		(duplicate_pad_numbers_are_jumpers no)
		(fp_line
			(start 0.508 0)
			(end -0.508 0)
			(stroke
				(width 0.2032)
				(type default)
			)
			(layer "F.SilkS")
		)
		(fp_rect
			(start -0.5842 1.3335)
			(end 0.5842 -1.3335)
			(stroke
				(width 0)
				(type default)
			)
			(fill no)
			(layer "F.CrtYd")
		)
		(fp_rect
			(start -0.5842 1.3335)
			(end 0.5842 -1.3335)
			(stroke
				(width 0)
				(type default)
			)
			(fill no)
			(layer "F.Fab")
		)
		(pad "1" smd custom
			(at 0 -0.762 180)
			(size 0.2159 0.2159)
			(layers "F.Cu" "F.Mask" "F.Paste")
			(net "P12V_SSD2")
			(options
				(clearance outline)
				(anchor circle)
			)
			(primitives
				(gr_poly
					(pts
						(arc
							(start -0.3302 -0.4318)
							(mid -0.402042 -0.402042)
							(end -0.4318 -0.3302)
						)
						(arc
							(start -0.4318 0.3302)
							(mid -0.402042 0.402042)
							(end -0.3302 0.4318)
						)
						(arc
							(start 0.3302 0.4318)
							(mid 0.402042 0.402042)
							(end 0.4318 0.3302)
						)
						(arc
							(start 0.4318 -0.3302)
							(mid 0.402042 -0.402042)
							(end 0.3302 -0.4318)
						)
					)
					(width 0)
					(fill yes)
				)
			)
		)
		(pad "2" smd custom
			(at 0 0.762 180)
			(size 0.2159 0.2159)
			(layers "F.Cu" "F.Mask" "F.Paste")
			(net "GND")
			(options
				(clearance outline)
				(anchor circle)
			)
			(primitives
				(gr_poly
					(pts
						(arc
							(start -0.3302 -0.4318)
							(mid -0.402042 -0.402042)
							(end -0.4318 -0.3302)
						)
						(arc
							(start -0.4318 0.3302)
							(mid -0.402042 0.402042)
							(end -0.3302 0.4318)
						)
						(arc
							(start 0.3302 0.4318)
							(mid 0.402042 0.402042)
							(end 0.4318 0.3302)
						)
						(arc
							(start 0.4318 -0.3302)
							(mid 0.402042 -0.402042)
							(end 0.3302 -0.4318)
						)
					)
					(width 0)
					(fill yes)
				)
			)
		)
	)
	(footprint ""
		(layer "F.Cu")
		(at 220.208094 -40.045894)
		(property "Reference" "SR1129"
			(at 0 0 0)
			(layer "F.SilkS")
			(hide yes)
			(effects
				(font
					(size 1.27 1.27)
				)
			)
		)
		(property "Value" "4K7R2F-GP"
			(at 0.064008 -3.993896 0)
			(unlocked yes)
			(layer "F.Fab")
			(hide yes)
			(effects
				(font
					(size 1.016 1.016)
					(thickness 0.1524)
				)
			)
		)
		(property "Device Type" "R402H16"
			(at 0.064008 -5.517896 0)
			(unlocked yes)
			(layer "F.Fab")
			(hide yes)
			(effects
				(font
					(size 1.016 1.016)
					(thickness 0.1524)
				)
			)
		)
		(duplicate_pad_numbers_are_jumpers no)
		(fp_line
			(start -0.508 -0.9398)
			(end -0.508 0.9398)
			(stroke
				(width 0.1524)
				(type default)
			)
			(layer "F.SilkS")
		)
		(fp_line
			(start 0.508 -0.9398)
			(end -0.508 -0.9398)
			(stroke
				(width 0.1524)
				(type default)
			)
			(layer "F.SilkS")
		)
		(fp_rect
			(start -0.508 0.9398)
			(end 0.508 -0.9398)
			(stroke
				(width 0)
				(type default)
			)
			(fill no)
			(layer "F.CrtYd")
		)
		(fp_rect
			(start -0.508 0.9398)
			(end 0.508 -0.9398)
			(stroke
				(width 0)
				(type default)
			)
			(fill no)
			(layer "F.Fab")
		)
		(pad "1" smd custom
			(at 0 -0.4445)
			(size 0.1397 0.1397)
			(layers "F.Cu" "F.Mask" "F.Paste")
			(net "P3V3")
			(options
				(clearance outline)
				(anchor circle)
			)
			(primitives
				(gr_poly
					(pts
						(arc
							(start -0.1778 -0.2794)
							(mid -0.249642 -0.249642)
							(end -0.2794 -0.1778)
						)
						(arc
							(start -0.2794 0.1778)
							(mid -0.249642 0.249642)
							(end -0.1778 0.2794)
						)
						(arc
							(start 0.1778 0.2794)
							(mid 0.249642 0.249642)
							(end 0.2794 0.1778)
						)
						(arc
							(start 0.2794 -0.1778)
							(mid 0.249642 -0.249642)
							(end 0.1778 -0.2794)
						)
					)
					(width 0)
					(fill yes)
				)
			)
		)
		(pad "2" smd custom
			(at 0 0.4445)
			(size 0.1397 0.1397)
			(layers "F.Cu" "F.Mask" "F.Paste")
			(net "SSD4_CLK0_OE_MOS_N")
			(options
				(clearance outline)
				(anchor circle)
			)
			(primitives
				(gr_poly
					(pts
						(arc
							(start -0.1778 -0.2794)
							(mid -0.249642 -0.249642)
							(end -0.2794 -0.1778)
						)
						(arc
							(start -0.2794 0.1778)
							(mid -0.249642 0.249642)
							(end -0.1778 0.2794)
						)
						(arc
							(start 0.1778 0.2794)
							(mid 0.249642 0.249642)
							(end 0.2794 0.1778)
						)
						(arc
							(start 0.2794 -0.1778)
							(mid 0.249642 -0.249642)
							(end 0.1778 -0.2794)
						)
					)
					(width 0)
					(fill yes)
				)
			)
		)
	)
	(footprint ""
		(layer "F.Cu")
		(at 228.281992 -346.833952 180)
		(property "Reference" "SR1124"
			(at 0 0 180)
			(layer "F.SilkS")
			(hide yes)
			(effects
				(font
					(size 1.27 1.27)
				)
			)
		)
		(property "Value" "4K7R2J-2-GP"
			(at 0.064008 -3.993896 180)
			(unlocked yes)
			(layer "F.Fab")
			(hide yes)
			(effects
				(font
					(size 1.016 1.016)
					(thickness 0.1524)
				)
			)
		)
		(property "Device Type" "R402H16"
			(at 0.064008 -5.517896 180)
			(unlocked yes)
			(layer "F.Fab")
			(hide yes)
			(effects
				(font
					(size 1.016 1.016)
					(thickness 0.1524)
				)
			)
		)
		(duplicate_pad_numbers_are_jumpers no)
		(fp_line
			(start 0.508 -0.9398)
			(end -0.508 -0.9398)
			(stroke
				(width 0.1524)
				(type default)
			)
			(layer "F.SilkS")
		)
		(fp_line
			(start -0.508 -0.9398)
			(end -0.508 0.9398)
			(stroke
				(width 0.1524)
				(type default)
			)
			(layer "F.SilkS")
		)
		(fp_rect
			(start -0.508 0.9398)
			(end 0.508 -0.9398)
			(stroke
				(width 0)
				(type default)
			)
			(fill no)
			(layer "F.CrtYd")
		)
		(fp_rect
			(start -0.508 0.9398)
			(end 0.508 -0.9398)
			(stroke
				(width 0)
				(type default)
			)
			(fill no)
			(layer "F.Fab")
		)
		(pad "1" smd custom
			(at 0 -0.4445 180)
			(size 0.1397 0.1397)
			(layers "F.Cu" "F.Mask" "F.Paste")
			(net "P3V3")
			(options
				(clearance outline)
				(anchor circle)
			)
			(primitives
				(gr_poly
					(pts
						(arc
							(start -0.1778 -0.2794)
							(mid -0.249642 -0.249642)
							(end -0.2794 -0.1778)
						)
						(arc
							(start -0.2794 0.1778)
							(mid -0.249642 0.249642)
							(end -0.1778 0.2794)
						)
						(arc
							(start 0.1778 0.2794)
							(mid 0.249642 0.249642)
							(end 0.2794 0.1778)
						)
						(arc
							(start 0.2794 -0.1778)
							(mid 0.249642 -0.249642)
							(end 0.1778 -0.2794)
						)
					)
					(width 0)
					(fill yes)
				)
			)
		)
		(pad "2" smd custom
			(at 0 0.4445 180)
			(size 0.1397 0.1397)
			(layers "F.Cu" "F.Mask" "F.Paste")
			(net "SSD_ACT_DR1")
			(options
				(clearance outline)
				(anchor circle)
			)
			(primitives
				(gr_poly
					(pts
						(arc
							(start -0.1778 -0.2794)
							(mid -0.249642 -0.249642)
							(end -0.2794 -0.1778)
						)
						(arc
							(start -0.2794 0.1778)
							(mid -0.249642 0.249642)
							(end -0.1778 0.2794)
						)
						(arc
							(start 0.1778 0.2794)
							(mid 0.249642 0.249642)
							(end 0.2794 0.1778)
						)
						(arc
							(start 0.2794 -0.1778)
							(mid 0.249642 -0.249642)
							(end 0.1778 -0.2794)
						)
					)
					(width 0)
					(fill yes)
				)
			)
		)
	)
	(footprint ""
		(layer "F.Cu")
		(at 74.0664 -366.522)
		(property "Reference" "SR985"
			(at 0 0 0)
			(layer "F.SilkS")
			(hide yes)
			(effects
				(font
					(size 1.27 1.27)
				)
			)
		)
		(property "Value" "2KR2F-3-GP"
			(at 0.064008 -3.993896 0)
			(unlocked yes)
			(layer "F.Fab")
			(hide yes)
			(effects
				(font
					(size 1.016 1.016)
					(thickness 0.1524)
				)
			)
		)
		(property "Device Type" "R402H16"
			(at 0.064008 -5.517896 0)
			(unlocked yes)
			(layer "F.Fab")
			(hide yes)
			(effects
				(font
					(size 1.016 1.016)
					(thickness 0.1524)
				)
			)
		)
		(duplicate_pad_numbers_are_jumpers no)
		(fp_line
			(start -0.508 -0.9398)
			(end -0.508 0.9398)
			(stroke
				(width 0.1524)
				(type default)
			)
			(layer "F.SilkS")
		)
		(fp_line
			(start 0.508 -0.9398)
			(end -0.508 -0.9398)
			(stroke
				(width 0.1524)
				(type default)
			)
			(layer "F.SilkS")
		)
		(fp_rect
			(start -0.508 0.9398)
			(end 0.508 -0.9398)
			(stroke
				(width 0)
				(type default)
			)
			(fill no)
			(layer "F.CrtYd")
		)
		(fp_rect
			(start -0.508 0.9398)
			(end 0.508 -0.9398)
			(stroke
				(width 0)
				(type default)
			)
			(fill no)
			(layer "F.Fab")
		)
		(pad "1" smd custom
			(at 0 -0.4445)
			(size 0.1397 0.1397)
			(layers "F.Cu" "F.Mask" "F.Paste")
			(net "P3V3")
			(options
				(clearance outline)
				(anchor circle)
			)
			(primitives
				(gr_poly
					(pts
						(arc
							(start -0.1778 -0.2794)
							(mid -0.249642 -0.249642)
							(end -0.2794 -0.1778)
						)
						(arc
							(start -0.2794 0.1778)
							(mid -0.249642 0.249642)
							(end -0.1778 0.2794)
						)
						(arc
							(start 0.1778 0.2794)
							(mid 0.249642 0.249642)
							(end 0.2794 0.1778)
						)
						(arc
							(start 0.2794 -0.1778)
							(mid 0.249642 -0.249642)
							(end 0.1778 -0.2794)
						)
					)
					(width 0)
					(fill yes)
				)
			)
		)
		(pad "2" smd custom
			(at 0 0.4445)
			(size 0.1397 0.1397)
			(layers "F.Cu" "F.Mask" "F.Paste")
			(net "SCL_DR10")
			(options
				(clearance outline)
				(anchor circle)
			)
			(primitives
				(gr_poly
					(pts
						(arc
							(start -0.1778 -0.2794)
							(mid -0.249642 -0.249642)
							(end -0.2794 -0.1778)
						)
						(arc
							(start -0.2794 0.1778)
							(mid -0.249642 0.249642)
							(end -0.1778 0.2794)
						)
						(arc
							(start 0.1778 0.2794)
							(mid 0.249642 0.249642)
							(end 0.2794 0.1778)
						)
						(arc
							(start 0.2794 -0.1778)
							(mid 0.249642 -0.249642)
							(end 0.1778 -0.2794)
						)
					)
					(width 0)
					(fill yes)
				)
			)
		)
	)
	(footprint ""
		(layer "F.Cu")
		(at 213.741 -431.927)
		(property "Reference" "PC1280"
			(at 0 0 0)
			(layer "F.SilkS")
			(hide yes)
			(effects
				(font
					(size 1.27 1.27)
				)
			)
		)
		(property "Value" "SCD1U16V2KX-3GP"
			(at 1.1811 -2.7051 0)
			(unlocked yes)
			(layer "F.Fab")
			(hide yes)
			(effects
				(font
					(size 1.016 1.016)
					(thickness 0.1524)
				)
			)
		)
		(property "Device Type" "C402H22"
			(at 1.1811 -4.2291 0)
			(unlocked yes)
			(layer "F.Fab")
			(hide yes)
			(effects
				(font
					(size 1.016 1.016)
					(thickness 0.1524)
				)
			)
		)
		(duplicate_pad_numbers_are_jumpers no)
		(fp_rect
			(start -0.4318 0.9525)
			(end 0.4318 -0.9525)
			(stroke
				(width 0)
				(type default)
			)
			(fill no)
			(layer "F.CrtYd")
		)
		(fp_rect
			(start -0.4318 0.9525)
			(end 0.4318 -0.9525)
			(stroke
				(width 0)
				(type default)
			)
			(fill no)
			(layer "F.Fab")
		)
		(pad "1" smd custom
			(at 0 -0.4445)
			(size 0.1524 0.1524)
			(layers "F.Cu" "F.Mask" "F.Paste")
			(net "P3V3_OUT")
			(options
				(clearance outline)
				(anchor circle)
			)
			(primitives
				(gr_poly
					(pts
						(arc
							(start 0.3048 -0.2032)
							(mid 0.275042 -0.275042)
							(end 0.2032 -0.3048)
						)
						(arc
							(start -0.2032 -0.3048)
							(mid -0.275042 -0.275042)
							(end -0.3048 -0.2032)
						)
						(arc
							(start -0.3048 0.2032)
							(mid -0.275042 0.275042)
							(end -0.2032 0.3048)
						)
						(arc
							(start 0.2032 0.3048)
							(mid 0.275042 0.275042)
							(end 0.3048 0.2032)
						)
					)
					(width 0)
					(fill yes)
				)
			)
		)
		(pad "2" smd custom
			(at 0 0.4445)
			(size 0.1524 0.1524)
			(layers "F.Cu" "F.Mask" "F.Paste")
			(net "GND")
			(options
				(clearance outline)
				(anchor circle)
			)
			(primitives
				(gr_poly
					(pts
						(arc
							(start 0.3048 -0.2032)
							(mid 0.275042 -0.275042)
							(end 0.2032 -0.3048)
						)
						(arc
							(start -0.2032 -0.3048)
							(mid -0.275042 -0.275042)
							(end -0.3048 -0.2032)
						)
						(arc
							(start -0.3048 0.2032)
							(mid -0.275042 0.275042)
							(end -0.2032 0.3048)
						)
						(arc
							(start 0.2032 0.3048)
							(mid 0.275042 0.275042)
							(end 0.3048 0.2032)
						)
					)
					(width 0)
					(fill yes)
				)
			)
		)
	)
)
